(kicad_pcb
	(version 20260206)
	(generator "pcbnew")
	(generator_version "10.0")
	(general
		(thickness 1.6)
		(legacy_teardrops no)
	)
	(paper "A4")
	(title_block
		(title "03242023_DA0F0TMBIJ0_F0T_Motherboard_J_brd_V01_OCP.brd")
		(comment 1 "Grand Teton / footprints 3317-3323 of 6105")
	)
	(layers
		(0 "F.Cu" signal "TOP")
		(4 "In1.Cu" signal "GND")
		(6 "In2.Cu" signal "IN1")
		(8 "In3.Cu" signal "GND1")
		(10 "In4.Cu" signal "IN2")
		(12 "In5.Cu" signal "GND2")
		(14 "In6.Cu" signal "IN3")
		(16 "In7.Cu" signal "GND3")
		(18 "In8.Cu" signal "VCC")
		(20 "In9.Cu" signal "VCC1")
		(22 "In10.Cu" signal "GND4")
		(24 "In11.Cu" signal "IN4")
		(26 "In12.Cu" signal "GND5")
		(28 "In13.Cu" signal "IN5")
		(30 "In14.Cu" signal "GND6")
		(32 "In15.Cu" signal "IN6")
		(34 "In16.Cu" signal "GND7")
		(2 "B.Cu" signal "BOTTOM")
		(9 "F.Adhes" user "F.Adhesive")
		(11 "B.Adhes" user "B.Adhesive")
		(13 "F.Paste" user "Package Geometry/Pastemask Top")
		(15 "B.Paste" user "Package Geometry/Pastemask Bottom")
		(5 "F.SilkS" user "Ref Des/Silkscreen Top")
		(7 "B.SilkS" user "Ref Des/Silkscreen Bottom")
		(1 "F.Mask" user "Board Geometry/Soldermask Top")
		(3 "B.Mask" user "Board Geometry/Soldermask Bottom")
		(17 "Dwgs.User" user "User.Drawings")
		(19 "Cmts.User" user "User.Comments")
		(21 "Eco1.User" user "User.Eco1")
		(23 "Eco2.User" user "User.Eco2")
		(25 "Edge.Cuts" user "Board Geometry/Outline")
		(27 "Margin" user)
		(31 "F.CrtYd" user "Package Geometry/Place Bound Top")
		(29 "B.CrtYd" user "Package Geometry/Place Bound Bottom")
		(35 "F.Fab" user "Ref Des/Assembly Top")
		(33 "B.Fab" user "Ref Des/Assembly Bottom")
	)
	(footprint ""
		(layer "F.Cu")
		(at 107.2896 -249.320558 -90)
		(property "Reference" "C307"
			(at 0 0 270)
			(layer "F.SilkS")
			(hide yes)
			(effects
				(font
					(size 1.27 1.27)
				)
			)
		)
		(property "Value" ""
			(at 0 0 270)
			(layer "F.Fab")
			(effects
				(font
					(size 1.27 1.27)
				)
			)
		)
		(duplicate_pad_numbers_are_jumpers no)
		(fp_line
			(start -0.7874 0.4064)
			(end -0.7874 -0.4064)
			(stroke
				(width 0.1524)
				(type default)
			)
			(layer "F.SilkS")
		)
		(fp_line
			(start 0.7874 0.4064)
			(end -0.7874 0.4064)
			(stroke
				(width 0.1524)
				(type default)
			)
			(layer "F.SilkS")
		)
		(fp_line
			(start -0.7874 -0.4064)
			(end 0.7874 -0.4064)
			(stroke
				(width 0.1524)
				(type default)
			)
			(layer "F.SilkS")
		)
		(fp_line
			(start 0.7874 -0.4064)
			(end 0.7874 0.4064)
			(stroke
				(width 0.1524)
				(type default)
			)
			(layer "F.SilkS")
		)
		(fp_line
			(start -0.67945 0.3048)
			(end -0.67945 -0.305054)
			(stroke
				(width 0.1)
				(type default)
			)
			(layer "F.Fab")
		)
		(fp_line
			(start -0.12065 0.3048)
			(end -0.67945 0.3048)
			(stroke
				(width 0.1)
				(type default)
			)
			(layer "F.Fab")
		)
		(fp_line
			(start 0.120396 0.3048)
			(end 0.120396 0.2794)
			(stroke
				(width 0.1)
				(type default)
			)
			(layer "F.Fab")
		)
		(fp_line
			(start 0.67945 0.3048)
			(end 0.120396 0.3048)
			(stroke
				(width 0.1)
				(type default)
			)
			(layer "F.Fab")
		)
		(fp_line
			(start -0.12065 0.2794)
			(end -0.12065 0.3048)
			(stroke
				(width 0.1)
				(type default)
			)
			(layer "F.Fab")
		)
		(fp_line
			(start 0.120396 0.2794)
			(end -0.12065 0.2794)
			(stroke
				(width 0.1)
				(type default)
			)
			(layer "F.Fab")
		)
		(fp_line
			(start -0.12065 -0.2794)
			(end 0.12065 -0.2794)
			(stroke
				(width 0.1)
				(type default)
			)
			(layer "F.Fab")
		)
		(fp_line
			(start 0.12065 -0.2794)
			(end 0.12065 -0.3048)
			(stroke
				(width 0.1)
				(type default)
			)
			(layer "F.Fab")
		)
		(fp_line
			(start 0.12065 -0.3048)
			(end 0.67945 -0.3048)
			(stroke
				(width 0.1)
				(type default)
			)
			(layer "F.Fab")
		)
		(fp_line
			(start 0.67945 -0.3048)
			(end 0.67945 0.3048)
			(stroke
				(width 0.1)
				(type default)
			)
			(layer "F.Fab")
		)
		(fp_line
			(start -0.67945 -0.305054)
			(end -0.12065 -0.305054)
			(stroke
				(width 0.1)
				(type default)
			)
			(layer "F.Fab")
		)
		(fp_line
			(start -0.12065 -0.305054)
			(end -0.12065 -0.2794)
			(stroke
				(width 0.1)
				(type default)
			)
			(layer "F.Fab")
		)
		(pad "1" smd circle
			(at -0.40005 0 270)
			(size 0 0)
			(layers "F.Cu" "F.Mask" "F.Paste")
			(net "PVCCIN_CPU1")
		)
		(pad "2" smd circle
			(at 0.40005 0 270)
			(size 0 0)
			(layers "F.Cu" "F.Mask" "F.Paste")
			(net "GND")
		)
	)
	(footprint ""
		(layer "F.Cu")
		(at 194.856608 -400.784822 180)
		(property "Reference" "PR3914"
			(at 0 0 180)
			(layer "F.SilkS")
			(hide yes)
			(effects
				(font
					(size 1.27 1.27)
				)
			)
		)
		(property "Value" ""
			(at 0 0 180)
			(layer "F.Fab")
			(effects
				(font
					(size 1.27 1.27)
				)
			)
		)
		(duplicate_pad_numbers_are_jumpers no)
		(fp_line
			(start 0.7874 0.4064)
			(end -0.7874 0.4064)
			(stroke
				(width 0.1524)
				(type default)
			)
			(layer "F.SilkS")
		)
		(fp_line
			(start 0.7874 -0.4064)
			(end 0.7874 0.4064)
			(stroke
				(width 0.1524)
				(type default)
			)
			(layer "F.SilkS")
		)
		(fp_line
			(start -0.7874 0.4064)
			(end -0.7874 -0.4064)
			(stroke
				(width 0.1524)
				(type default)
			)
			(layer "F.SilkS")
		)
		(fp_line
			(start -0.7874 -0.4064)
			(end 0.7874 -0.4064)
			(stroke
				(width 0.1524)
				(type default)
			)
			(layer "F.SilkS")
		)
		(fp_line
			(start 0.67945 0.3048)
			(end 0.120396 0.3048)
			(stroke
				(width 0.1)
				(type default)
			)
			(layer "F.Fab")
		)
		(fp_line
			(start 0.67945 -0.3048)
			(end 0.67945 0.3048)
			(stroke
				(width 0.1)
				(type default)
			)
			(layer "F.Fab")
		)
		(fp_line
			(start 0.12065 -0.2794)
			(end 0.12065 -0.3048)
			(stroke
				(width 0.1)
				(type default)
			)
			(layer "F.Fab")
		)
		(fp_line
			(start 0.12065 -0.3048)
			(end 0.67945 -0.3048)
			(stroke
				(width 0.1)
				(type default)
			)
			(layer "F.Fab")
		)
		(fp_line
			(start 0.120396 0.3048)
			(end 0.120396 0.2794)
			(stroke
				(width 0.1)
				(type default)
			)
			(layer "F.Fab")
		)
		(fp_line
			(start 0.120396 0.2794)
			(end -0.12065 0.2794)
			(stroke
				(width 0.1)
				(type default)
			)
			(layer "F.Fab")
		)
		(fp_line
			(start -0.12065 0.3048)
			(end -0.67945 0.3048)
			(stroke
				(width 0.1)
				(type default)
			)
			(layer "F.Fab")
		)
		(fp_line
			(start -0.12065 0.2794)
			(end -0.12065 0.3048)
			(stroke
				(width 0.1)
				(type default)
			)
			(layer "F.Fab")
		)
		(fp_line
			(start -0.12065 -0.2794)
			(end 0.12065 -0.2794)
			(stroke
				(width 0.1)
				(type default)
			)
			(layer "F.Fab")
		)
		(fp_line
			(start -0.12065 -0.305054)
			(end -0.12065 -0.2794)
			(stroke
				(width 0.1)
				(type default)
			)
			(layer "F.Fab")
		)
		(fp_line
			(start -0.67945 0.3048)
			(end -0.67945 -0.305054)
			(stroke
				(width 0.1)
				(type default)
			)
			(layer "F.Fab")
		)
		(fp_line
			(start -0.67945 -0.305054)
			(end -0.12065 -0.305054)
			(stroke
				(width 0.1)
				(type default)
			)
			(layer "F.Fab")
		)
		(pad "1" smd circle
			(at -0.40005 0 180)
			(size 0 0)
			(layers "F.Cu" "F.Mask" "F.Paste")
			(net "HSC_CS_1")
		)
		(pad "2" smd circle
			(at 0.40005 0 180)
			(size 0 0)
			(layers "F.Cu" "F.Mask" "F.Paste")
			(net "AGND_HSC")
		)
	)
	(footprint ""
		(layer "F.Cu")
		(at 30.392878 -17.623536 90)
		(property "Reference" "C817"
			(at 0 0 90)
			(layer "F.SilkS")
			(hide yes)
			(effects
				(font
					(size 1.27 1.27)
				)
			)
		)
		(property "Value" ""
			(at 0 0 90)
			(layer "F.Fab")
			(effects
				(font
					(size 1.27 1.27)
				)
			)
		)
		(duplicate_pad_numbers_are_jumpers no)
		(fp_line
			(start 0.299974 -0.150114)
			(end 0.299974 0.150114)
			(stroke
				(width 0.1)
				(type default)
			)
			(layer "F.Fab")
		)
		(fp_line
			(start -0.299974 -0.150114)
			(end 0.299974 -0.150114)
			(stroke
				(width 0.1)
				(type default)
			)
			(layer "F.Fab")
		)
		(fp_line
			(start 0.299974 0.150114)
			(end -0.299974 0.150114)
			(stroke
				(width 0.1)
				(type default)
			)
			(layer "F.Fab")
		)
		(fp_line
			(start -0.299974 0.150114)
			(end -0.299974 -0.150114)
			(stroke
				(width 0.1)
				(type default)
			)
			(layer "F.Fab")
		)
		(pad "1" smd rect
			(at -0.2667 0 90)
			(size 0.3048 0.381)
			(layers "F.Cu" "F.Mask" "F.Paste")
			(net "P5E_CPU1_PE1_TX_C_DP<10>")
		)
		(pad "2" smd rect
			(at 0.2667 0 90)
			(size 0.3048 0.381)
			(layers "F.Cu" "F.Mask" "F.Paste")
			(net "P5E_CPU1_PE1_TX_DP<10>")
		)
	)
	(footprint ""
		(layer "F.Cu")
		(at 80.77073 -59.372246 -90)
		(property "Reference" "PR3795"
			(at 0 0 270)
			(layer "F.SilkS")
			(hide yes)
			(effects
				(font
					(size 1.27 1.27)
				)
			)
		)
		(property "Value" ""
			(at 0 0 270)
			(layer "F.Fab")
			(effects
				(font
					(size 1.27 1.27)
				)
			)
		)
		(duplicate_pad_numbers_are_jumpers no)
		(fp_line
			(start -0.7874 0.4064)
			(end -0.7874 -0.4064)
			(stroke
				(width 0.1524)
				(type default)
			)
			(layer "F.SilkS")
		)
		(fp_line
			(start 0.7874 0.4064)
			(end -0.7874 0.4064)
			(stroke
				(width 0.1524)
				(type default)
			)
			(layer "F.SilkS")
		)
		(fp_line
			(start -0.7874 -0.4064)
			(end 0.7874 -0.4064)
			(stroke
				(width 0.1524)
				(type default)
			)
			(layer "F.SilkS")
		)
		(fp_line
			(start 0.7874 -0.4064)
			(end 0.7874 0.4064)
			(stroke
				(width 0.1524)
				(type default)
			)
			(layer "F.SilkS")
		)
		(fp_line
			(start -0.67945 0.3048)
			(end -0.67945 -0.305054)
			(stroke
				(width 0.1)
				(type default)
			)
			(layer "F.Fab")
		)
		(fp_line
			(start -0.12065 0.3048)
			(end -0.67945 0.3048)
			(stroke
				(width 0.1)
				(type default)
			)
			(layer "F.Fab")
		)
		(fp_line
			(start 0.120396 0.3048)
			(end 0.120396 0.2794)
			(stroke
				(width 0.1)
				(type default)
			)
			(layer "F.Fab")
		)
		(fp_line
			(start 0.67945 0.3048)
			(end 0.120396 0.3048)
			(stroke
				(width 0.1)
				(type default)
			)
			(layer "F.Fab")
		)
		(fp_line
			(start -0.12065 0.2794)
			(end -0.12065 0.3048)
			(stroke
				(width 0.1)
				(type default)
			)
			(layer "F.Fab")
		)
		(fp_line
			(start 0.120396 0.2794)
			(end -0.12065 0.2794)
			(stroke
				(width 0.1)
				(type default)
			)
			(layer "F.Fab")
		)
		(fp_line
			(start -0.12065 -0.2794)
			(end 0.12065 -0.2794)
			(stroke
				(width 0.1)
				(type default)
			)
			(layer "F.Fab")
		)
		(fp_line
			(start 0.12065 -0.2794)
			(end 0.12065 -0.3048)
			(stroke
				(width 0.1)
				(type default)
			)
			(layer "F.Fab")
		)
		(fp_line
			(start 0.12065 -0.3048)
			(end 0.67945 -0.3048)
			(stroke
				(width 0.1)
				(type default)
			)
			(layer "F.Fab")
		)
		(fp_line
			(start 0.67945 -0.3048)
			(end 0.67945 0.3048)
			(stroke
				(width 0.1)
				(type default)
			)
			(layer "F.Fab")
		)
		(fp_line
			(start -0.67945 -0.305054)
			(end -0.12065 -0.305054)
			(stroke
				(width 0.1)
				(type default)
			)
			(layer "F.Fab")
		)
		(fp_line
			(start -0.12065 -0.305054)
			(end -0.12065 -0.2794)
			(stroke
				(width 0.1)
				(type default)
			)
			(layer "F.Fab")
		)
		(pad "1" smd circle
			(at -0.40005 0 270)
			(size 0 0)
			(layers "F.Cu" "F.Mask" "F.Paste")
			(net "P3V3_AUX")
		)
		(pad "2" smd circle
			(at 0.40005 0 270)
			(size 0 0)
			(layers "F.Cu" "F.Mask" "F.Paste")
			(net "P3V3_OCP_UV_2")
		)
	)
	(footprint ""
		(layer "F.Cu")
		(at 193.60388 -108.765848)
		(property "Reference" "R1558"
			(at 0 0 0)
			(layer "F.SilkS")
			(hide yes)
			(effects
				(font
					(size 1.27 1.27)
				)
			)
		)
		(property "Value" ""
			(at 0 0 0)
			(layer "F.Fab")
			(effects
				(font
					(size 1.27 1.27)
				)
			)
		)
		(duplicate_pad_numbers_are_jumpers no)
		(fp_line
			(start -0.7874 -0.4064)
			(end 0.7874 -0.4064)
			(stroke
				(width 0.1524)
				(type default)
			)
			(layer "F.SilkS")
		)
		(fp_line
			(start -0.7874 0.4064)
			(end -0.7874 -0.4064)
			(stroke
				(width 0.1524)
				(type default)
			)
			(layer "F.SilkS")
		)
		(fp_line
			(start 0.7874 -0.4064)
			(end 0.7874 0.4064)
			(stroke
				(width 0.1524)
				(type default)
			)
			(layer "F.SilkS")
		)
		(fp_line
			(start 0.7874 0.4064)
			(end -0.7874 0.4064)
			(stroke
				(width 0.1524)
				(type default)
			)
			(layer "F.SilkS")
		)
		(fp_line
			(start -0.67945 -0.305054)
			(end -0.12065 -0.305054)
			(stroke
				(width 0.1)
				(type default)
			)
			(layer "F.Fab")
		)
		(fp_line
			(start -0.67945 0.3048)
			(end -0.67945 -0.305054)
			(stroke
				(width 0.1)
				(type default)
			)
			(layer "F.Fab")
		)
		(fp_line
			(start -0.12065 -0.305054)
			(end -0.12065 -0.2794)
			(stroke
				(width 0.1)
				(type default)
			)
			(layer "F.Fab")
		)
		(fp_line
			(start -0.12065 -0.2794)
			(end 0.12065 -0.2794)
			(stroke
				(width 0.1)
				(type default)
			)
			(layer "F.Fab")
		)
		(fp_line
			(start -0.12065 0.2794)
			(end -0.12065 0.3048)
			(stroke
				(width 0.1)
				(type default)
			)
			(layer "F.Fab")
		)
		(fp_line
			(start -0.12065 0.3048)
			(end -0.67945 0.3048)
			(stroke
				(width 0.1)
				(type default)
			)
			(layer "F.Fab")
		)
		(fp_line
			(start 0.120396 0.2794)
			(end -0.12065 0.2794)
			(stroke
				(width 0.1)
				(type default)
			)
			(layer "F.Fab")
		)
		(fp_line
			(start 0.120396 0.3048)
			(end 0.120396 0.2794)
			(stroke
				(width 0.1)
				(type default)
			)
			(layer "F.Fab")
		)
		(fp_line
			(start 0.12065 -0.3048)
			(end 0.67945 -0.3048)
			(stroke
				(width 0.1)
				(type default)
			)
			(layer "F.Fab")
		)
		(fp_line
			(start 0.12065 -0.2794)
			(end 0.12065 -0.3048)
			(stroke
				(width 0.1)
				(type default)
			)
			(layer "F.Fab")
		)
		(fp_line
			(start 0.67945 -0.3048)
			(end 0.67945 0.3048)
			(stroke
				(width 0.1)
				(type default)
			)
			(layer "F.Fab")
		)
		(fp_line
			(start 0.67945 0.3048)
			(end 0.120396 0.3048)
			(stroke
				(width 0.1)
				(type default)
			)
			(layer "F.Fab")
		)
		(pad "1" smd circle
			(at -0.40005 0)
			(size 0 0)
			(layers "F.Cu" "F.Mask" "F.Paste")
			(net "FM_CPU_RMCA_CATERR_LVT3_R_N")
		)
		(pad "2" smd circle
			(at 0.40005 0)
			(size 0 0)
			(layers "F.Cu" "F.Mask" "F.Paste")
			(net "P3V3_AUX")
		)
	)
	(footprint ""
		(layer "F.Cu")
		(at 205.6892 -92.6338 -90)
		(property "Reference" "R4775"
			(at 0 0 270)
			(layer "F.SilkS")
			(hide yes)
			(effects
				(font
					(size 1.27 1.27)
				)
			)
		)
		(property "Value" ""
			(at 0 0 270)
			(layer "F.Fab")
			(effects
				(font
					(size 1.27 1.27)
				)
			)
		)
		(duplicate_pad_numbers_are_jumpers no)
		(fp_line
			(start -0.7874 0.4064)
			(end -0.7874 -0.4064)
			(stroke
				(width 0.1524)
				(type default)
			)
			(layer "F.SilkS")
		)
		(fp_line
			(start 0.7874 0.4064)
			(end -0.7874 0.4064)
			(stroke
				(width 0.1524)
				(type default)
			)
			(layer "F.SilkS")
		)
		(fp_line
			(start -0.7874 -0.4064)
			(end 0.7874 -0.4064)
			(stroke
				(width 0.1524)
				(type default)
			)
			(layer "F.SilkS")
		)
		(fp_line
			(start 0.7874 -0.4064)
			(end 0.7874 0.4064)
			(stroke
				(width 0.1524)
				(type default)
			)
			(layer "F.SilkS")
		)
		(fp_line
			(start -0.67945 0.3048)
			(end -0.67945 -0.305054)
			(stroke
				(width 0.1)
				(type default)
			)
			(layer "F.Fab")
		)
		(fp_line
			(start -0.12065 0.3048)
			(end -0.67945 0.3048)
			(stroke
				(width 0.1)
				(type default)
			)
			(layer "F.Fab")
		)
		(fp_line
			(start 0.120396 0.3048)
			(end 0.120396 0.2794)
			(stroke
				(width 0.1)
				(type default)
			)
			(layer "F.Fab")
		)
		(fp_line
			(start 0.67945 0.3048)
			(end 0.120396 0.3048)
			(stroke
				(width 0.1)
				(type default)
			)
			(layer "F.Fab")
		)
		(fp_line
			(start -0.12065 0.2794)
			(end -0.12065 0.3048)
			(stroke
				(width 0.1)
				(type default)
			)
			(layer "F.Fab")
		)
		(fp_line
			(start 0.120396 0.2794)
			(end -0.12065 0.2794)
			(stroke
				(width 0.1)
				(type default)
			)
			(layer "F.Fab")
		)
		(fp_line
			(start -0.12065 -0.2794)
			(end 0.12065 -0.2794)
			(stroke
				(width 0.1)
				(type default)
			)
			(layer "F.Fab")
		)
		(fp_line
			(start 0.12065 -0.2794)
			(end 0.12065 -0.3048)
			(stroke
				(width 0.1)
				(type default)
			)
			(layer "F.Fab")
		)
		(fp_line
			(start 0.12065 -0.3048)
			(end 0.67945 -0.3048)
			(stroke
				(width 0.1)
				(type default)
			)
			(layer "F.Fab")
		)
		(fp_line
			(start 0.67945 -0.3048)
			(end 0.67945 0.3048)
			(stroke
				(width 0.1)
				(type default)
			)
			(layer "F.Fab")
		)
		(fp_line
			(start -0.67945 -0.305054)
			(end -0.12065 -0.305054)
			(stroke
				(width 0.1)
				(type default)
			)
			(layer "F.Fab")
		)
		(fp_line
			(start -0.12065 -0.305054)
			(end -0.12065 -0.2794)
			(stroke
				(width 0.1)
				(type default)
			)
			(layer "F.Fab")
		)
		(pad "1" smd circle
			(at -0.40005 0 270)
			(size 0 0)
			(layers "F.Cu" "F.Mask" "F.Paste")
			(net "P12V_AUX_UV_ADR_TRIGGER")
		)
		(pad "2" smd circle
			(at 0.40005 0 270)
			(size 0 0)
			(layers "F.Cu" "F.Mask" "F.Paste")
			(net "GND")
		)
	)
	(footprint ""
		(layer "F.Cu")
		(at 21.920708 -162.20567 90)
		(property "Reference" "PR216"
			(at 0 0 90)
			(layer "F.SilkS")
			(hide yes)
			(effects
				(font
					(size 1.27 1.27)
				)
			)
		)
		(property "Value" ""
			(at 0 0 90)
			(layer "F.Fab")
			(effects
				(font
					(size 1.27 1.27)
				)
			)
		)
		(duplicate_pad_numbers_are_jumpers no)
		(fp_line
			(start 0.7874 -0.4064)
			(end 0.7874 0.4064)
			(stroke
				(width 0.1524)
				(type default)
			)
			(layer "F.SilkS")
		)
		(fp_line
			(start -0.7874 -0.4064)
			(end 0.7874 -0.4064)
			(stroke
				(width 0.1524)
				(type default)
			)
			(layer "F.SilkS")
		)
		(fp_line
			(start 0.7874 0.4064)
			(end -0.7874 0.4064)
			(stroke
				(width 0.1524)
				(type default)
			)
			(layer "F.SilkS")
		)
		(fp_line
			(start -0.7874 0.4064)
			(end -0.7874 -0.4064)
			(stroke
				(width 0.1524)
				(type default)
			)
			(layer "F.SilkS")
		)
		(fp_line
			(start -0.12065 -0.305054)
			(end -0.12065 -0.2794)
			(stroke
				(width 0.1)
				(type default)
			)
			(layer "F.Fab")
		)
		(fp_line
			(start -0.67945 -0.305054)
			(end -0.12065 -0.305054)
			(stroke
				(width 0.1)
				(type default)
			)
			(layer "F.Fab")
		)
		(fp_line
			(start 0.67945 -0.3048)
			(end 0.67945 0.3048)
			(stroke
				(width 0.1)
				(type default)
			)
			(layer "F.Fab")
		)
		(fp_line
			(start 0.12065 -0.3048)
			(end 0.67945 -0.3048)
			(stroke
				(width 0.1)
				(type default)
			)
			(layer "F.Fab")
		)
		(fp_line
			(start 0.12065 -0.2794)
			(end 0.12065 -0.3048)
			(stroke
				(width 0.1)
				(type default)
			)
			(layer "F.Fab")
		)
		(fp_line
			(start -0.12065 -0.2794)
			(end 0.12065 -0.2794)
			(stroke
				(width 0.1)
				(type default)
			)
			(layer "F.Fab")
		)
		(fp_line
			(start 0.120396 0.2794)
			(end -0.12065 0.2794)
			(stroke
				(width 0.1)
				(type default)
			)
			(layer "F.Fab")
		)
		(fp_line
			(start -0.12065 0.2794)
			(end -0.12065 0.3048)
			(stroke
				(width 0.1)
				(type default)
			)
			(layer "F.Fab")
		)
		(fp_line
			(start 0.67945 0.3048)
			(end 0.120396 0.3048)
			(stroke
				(width 0.1)
				(type default)
			)
			(layer "F.Fab")
		)
		(fp_line
			(start 0.120396 0.3048)
			(end 0.120396 0.2794)
			(stroke
				(width 0.1)
				(type default)
			)
			(layer "F.Fab")
		)
		(fp_line
			(start -0.12065 0.3048)
			(end -0.67945 0.3048)
			(stroke
				(width 0.1)
				(type default)
			)
			(layer "F.Fab")
		)
		(fp_line
			(start -0.67945 0.3048)
			(end -0.67945 -0.305054)
			(stroke
				(width 0.1)
				(type default)
			)
			(layer "F.Fab")
		)
		(pad "1" smd circle
			(at -0.40005 0 90)
			(size 0 0)
			(layers "F.Cu" "F.Mask" "F.Paste")
			(net "SH_PVCCD_HV_CPU1")
		)
		(pad "2" smd circle
			(at 0.40005 0 90)
			(size 0 0)
			(layers "F.Cu" "F.Mask" "F.Paste")
			(net "SH_PVCCD_HV_CPU1_R")
		)
	)
)
